# S9S_MB_2U (Grand Teton) — schematic netlist excerpt (pin names and nets, part order shuffled) for the footprints in the layout excerpt that follows; sources: Cadence DE-HDL packaged netlist, KiCad conversion of 03242023_DA0F0TMBIJ0_F0T_Motherboard_J_brd_V01_OCP.brd

R2343  Q_RES  10K 1% EMPTY  pkg 0402LF  page 213 : A = P5V_AUX_VCC ; B = PWRGD_P5V_AUX
R4405  Q_RES  4.75K 1% CHIP  pkg 0402LF  page 122 : A = P3V3 ; B = H_CPU0_MEMHOT_OUT_VT_N
C732  Q_CAP_DIFFBUS  DIFF BUS_0.22UF 6.3V 20% X6S  pkg C0201  page 176 : \1\ = P5E_CPU1_PE0_TX_C_DN<4> ; \2\ = P5E_CPU1_PE0_TX_DN<4>

(kicad_pcb
	(version 20260206)
	(generator "pcbnew")
	(generator_version "10.0")
	(general
		(thickness 1.6)
		(legacy_teardrops no)
	)
	(paper "A4")
	(title_block
		(title "03242023_DA0F0TMBIJ0_F0T_Motherboard_J_brd_V01_OCP.brd")
		(comment 1 "Grand Teton / footprints 141-143 of 6105")
	)
	(layers
		(0 "F.Cu" signal "TOP")
		(4 "In1.Cu" signal "GND")
		(6 "In2.Cu" signal "IN1")
		(8 "In3.Cu" signal "GND1")
		(10 "In4.Cu" signal "IN2")
		(12 "In5.Cu" signal "GND2")
		(14 "In6.Cu" signal "IN3")
		(16 "In7.Cu" signal "GND3")
		(18 "In8.Cu" signal "VCC")
		(20 "In9.Cu" signal "VCC1")
		(22 "In10.Cu" signal "GND4")
		(24 "In11.Cu" signal "IN4")
		(26 "In12.Cu" signal "GND5")
		(28 "In13.Cu" signal "IN5")
		(30 "In14.Cu" signal "GND6")
		(32 "In15.Cu" signal "IN6")
		(34 "In16.Cu" signal "GND7")
		(2 "B.Cu" signal "BOTTOM")
		(9 "F.Adhes" user "F.Adhesive")
		(11 "B.Adhes" user "B.Adhesive")
		(13 "F.Paste" user "Package Geometry/Pastemask Top")
		(15 "B.Paste" user "Package Geometry/Pastemask Bottom")
		(5 "F.SilkS" user "Ref Des/Silkscreen Top")
		(7 "B.SilkS" user "Ref Des/Silkscreen Bottom")
		(1 "F.Mask" user "Board Geometry/Soldermask Top")
		(3 "B.Mask" user "Board Geometry/Soldermask Bottom")
		(17 "Dwgs.User" user "User.Drawings")
		(19 "Cmts.User" user "User.Comments")
		(21 "Eco1.User" user "User.Eco1")
		(23 "Eco2.User" user "User.Eco2")
		(25 "Edge.Cuts" user "Board Geometry/Outline")
		(27 "Margin" user)
		(31 "F.CrtYd" user "Package Geometry/Place Bound Top")
		(29 "B.CrtYd" user "Package Geometry/Place Bound Bottom")
		(35 "F.Fab" user "Ref Des/Assembly Top")
		(33 "B.Fab" user "Ref Des/Assembly Bottom")
	)
	(footprint ""
		(layer "F.Cu")
		(at 130.73888 -92.674948 90)
		(property "Reference" "R4405"
			(at 0 0 90)
			(layer "F.SilkS")
			(hide yes)
			(effects
				(font
					(size 1.27 1.27)
				)
			)
		)
		(property "Value" ""
			(at 0 0 90)
			(layer "F.Fab")
			(effects
				(font
					(size 1.27 1.27)
				)
			)
		)
		(duplicate_pad_numbers_are_jumpers no)
		(fp_line
			(start 0.7874 -0.4064)
			(end 0.7874 0.4064)
			(stroke
				(width 0.1524)
				(type default)
			)
			(layer "F.SilkS")
		)
		(fp_line
			(start -0.7874 -0.4064)
			(end 0.7874 -0.4064)
			(stroke
				(width 0.1524)
				(type default)
			)
			(layer "F.SilkS")
		)
		(fp_line
			(start 0.7874 0.4064)
			(end -0.7874 0.4064)
			(stroke
				(width 0.1524)
				(type default)
			)
			(layer "F.SilkS")
		)
		(fp_line
			(start -0.7874 0.4064)
			(end -0.7874 -0.4064)
			(stroke
				(width 0.1524)
				(type default)
			)
			(layer "F.SilkS")
		)
		(fp_line
			(start -0.12065 -0.305054)
			(end -0.12065 -0.2794)
			(stroke
				(width 0.1)
				(type default)
			)
			(layer "F.Fab")
		)
		(fp_line
			(start -0.67945 -0.305054)
			(end -0.12065 -0.305054)
			(stroke
				(width 0.1)
				(type default)
			)
			(layer "F.Fab")
		)
		(fp_line
			(start 0.67945 -0.3048)
			(end 0.67945 0.3048)
			(stroke
				(width 0.1)
				(type default)
			)
			(layer "F.Fab")
		)
		(fp_line
			(start 0.12065 -0.3048)
			(end 0.67945 -0.3048)
			(stroke
				(width 0.1)
				(type default)
			)
			(layer "F.Fab")
		)
		(fp_line
			(start 0.12065 -0.2794)
			(end 0.12065 -0.3048)
			(stroke
				(width 0.1)
				(type default)
			)
			(layer "F.Fab")
		)
		(fp_line
			(start -0.12065 -0.2794)
			(end 0.12065 -0.2794)
			(stroke
				(width 0.1)
				(type default)
			)
			(layer "F.Fab")
		)
		(fp_line
			(start 0.120396 0.2794)
			(end -0.12065 0.2794)
			(stroke
				(width 0.1)
				(type default)
			)
			(layer "F.Fab")
		)
		(fp_line
			(start -0.12065 0.2794)
			(end -0.12065 0.3048)
			(stroke
				(width 0.1)
				(type default)
			)
			(layer "F.Fab")
		)
		(fp_line
			(start 0.67945 0.3048)
			(end 0.120396 0.3048)
			(stroke
				(width 0.1)
				(type default)
			)
			(layer "F.Fab")
		)
		(fp_line
			(start 0.120396 0.3048)
			(end 0.120396 0.2794)
			(stroke
				(width 0.1)
				(type default)
			)
			(layer "F.Fab")
		)
		(fp_line
			(start -0.12065 0.3048)
			(end -0.67945 0.3048)
			(stroke
				(width 0.1)
				(type default)
			)
			(layer "F.Fab")
		)
		(fp_line
			(start -0.67945 0.3048)
			(end -0.67945 -0.305054)
			(stroke
				(width 0.1)
				(type default)
			)
			(layer "F.Fab")
		)
		(pad "1" smd circle
			(at -0.40005 0 90)
			(size 0 0)
			(layers "F.Cu" "F.Mask" "F.Paste")
			(net "P3V3")
		)
		(pad "2" smd circle
			(at 0.40005 0 90)
			(size 0 0)
			(layers "F.Cu" "F.Mask" "F.Paste")
			(net "H_CPU0_MEMHOT_OUT_VT_N")
		)
	)
	(footprint ""
		(layer "F.Cu")
		(at 81.650078 -402.371052 -90)
		(property "Reference" "C732"
			(at 0 0 270)
			(layer "F.SilkS")
			(hide yes)
			(effects
				(font
					(size 1.27 1.27)
				)
			)
		)
		(property "Value" ""
			(at 0 0 270)
			(layer "F.Fab")
			(effects
				(font
					(size 1.27 1.27)
				)
			)
		)
		(duplicate_pad_numbers_are_jumpers no)
		(fp_line
			(start -0.299974 0.150114)
			(end -0.299974 -0.150114)
			(stroke
				(width 0.1)
				(type default)
			)
			(layer "F.Fab")
		)
		(fp_line
			(start 0.299974 0.150114)
			(end -0.299974 0.150114)
			(stroke
				(width 0.1)
				(type default)
			)
			(layer "F.Fab")
		)
		(fp_line
			(start -0.299974 -0.150114)
			(end 0.299974 -0.150114)
			(stroke
				(width 0.1)
				(type default)
			)
			(layer "F.Fab")
		)
		(fp_line
			(start 0.299974 -0.150114)
			(end 0.299974 0.150114)
			(stroke
				(width 0.1)
				(type default)
			)
			(layer "F.Fab")
		)
		(pad "1" smd rect
			(at -0.2667 0 270)
			(size 0.3048 0.381)
			(layers "F.Cu" "F.Mask" "F.Paste")
			(net "P5E_CPU1_PE0_TX_C_DN<4>")
		)
		(pad "2" smd rect
			(at 0.2667 0 270)
			(size 0.3048 0.381)
			(layers "F.Cu" "F.Mask" "F.Paste")
			(net "P5E_CPU1_PE0_TX_DN<4>")
		)
	)
	(footprint ""
		(layer "F.Cu")
		(at 152.76322 -116.506752)
		(property "Reference" "R2343"
			(at 0 0 0)
			(layer "F.SilkS")
			(hide yes)
			(effects
				(font
					(size 1.27 1.27)
				)
			)
		)
		(property "Value" ""
			(at 0 0 0)
			(layer "F.Fab")
			(effects
				(font
					(size 1.27 1.27)
				)
			)
		)
		(duplicate_pad_numbers_are_jumpers no)
		(fp_line
			(start -0.7874 -0.4064)
			(end 0.7874 -0.4064)
			(stroke
				(width 0.1524)
				(type default)
			)
			(layer "F.SilkS")
		)
		(fp_line
			(start -0.7874 0.4064)
			(end -0.7874 -0.4064)
			(stroke
				(width 0.1524)
				(type default)
			)
			(layer "F.SilkS")
		)
		(fp_line
			(start 0.7874 -0.4064)
			(end 0.7874 0.4064)
			(stroke
				(width 0.1524)
				(type default)
			)
			(layer "F.SilkS")
		)
		(fp_line
			(start 0.7874 0.4064)
			(end -0.7874 0.4064)
			(stroke
				(width 0.1524)
				(type default)
			)
			(layer "F.SilkS")
		)
		(fp_line
			(start -0.67945 -0.305054)
			(end -0.12065 -0.305054)
			(stroke
				(width 0.1)
				(type default)
			)
			(layer "F.Fab")
		)
		(fp_line
			(start -0.67945 0.3048)
			(end -0.67945 -0.305054)
			(stroke
				(width 0.1)
				(type default)
			)
			(layer "F.Fab")
		)
		(fp_line
			(start -0.12065 -0.305054)
			(end -0.12065 -0.2794)
			(stroke
				(width 0.1)
				(type default)
			)
			(layer "F.Fab")
		)
		(fp_line
			(start -0.12065 -0.2794)
			(end 0.12065 -0.2794)
			(stroke
				(width 0.1)
				(type default)
			)
			(layer "F.Fab")
		)
		(fp_line
			(start -0.12065 0.2794)
			(end -0.12065 0.3048)
			(stroke
				(width 0.1)
				(type default)
			)
			(layer "F.Fab")
		)
		(fp_line
			(start -0.12065 0.3048)
			(end -0.67945 0.3048)
			(stroke
				(width 0.1)
				(type default)
			)
			(layer "F.Fab")
		)
		(fp_line
			(start 0.120396 0.2794)
			(end -0.12065 0.2794)
			(stroke
				(width 0.1)
				(type default)
			)
			(layer "F.Fab")
		)
		(fp_line
			(start 0.120396 0.3048)
			(end 0.120396 0.2794)
			(stroke
				(width 0.1)
				(type default)
			)
			(layer "F.Fab")
		)
		(fp_line
			(start 0.12065 -0.3048)
			(end 0.67945 -0.3048)
			(stroke
				(width 0.1)
				(type default)
			)
			(layer "F.Fab")
		)
		(fp_line
			(start 0.12065 -0.2794)
			(end 0.12065 -0.3048)
			(stroke
				(width 0.1)
				(type default)
			)
			(layer "F.Fab")
		)
		(fp_line
			(start 0.67945 -0.3048)
			(end 0.67945 0.3048)
			(stroke
				(width 0.1)
				(type default)
			)
			(layer "F.Fab")
		)
		(fp_line
			(start 0.67945 0.3048)
			(end 0.120396 0.3048)
			(stroke
				(width 0.1)
				(type default)
			)
			(layer "F.Fab")
		)
		(pad "1" smd circle
			(at -0.40005 0)
			(size 0 0)
			(layers "F.Cu" "F.Mask" "F.Paste")
			(net "P5V_AUX_VCC")
		)
		(pad "2" smd circle
			(at 0.40005 0)
			(size 0 0)
			(layers "F.Cu" "F.Mask" "F.Paste")
			(net "PWRGD_P5V_AUX")
		)
	)
)
